# T6G (Grand Teton) — schematic netlist excerpt (pin names and nets, part order shuffled) for the footprints in the layout excerpt that follows; sources: Cadence DE-HDL packaged netlist, KiCad conversion of 04192023_DAF0TMB3IC0_F0TG_MB_C_brd_V02_OCP.brd

C1108  Q_CAP  0.1UF 25V 10% X7R  pkg 0402  page 357 : A = P12V_OCP_SFF ; B = GND
R812  Q_RES  1K 1% CHIP  pkg 0201LF  page 185 : A = P1V8_CPU1_RT_1D ; B = SMB_RT_CPU1_P3_ROM_R_SCL
R4562  Q_RES  100K 1% EMPTY  pkg 0402LF  page 125 : A = P3V3_AUX ; B = SWB_HSC_PWRGD

(kicad_pcb
	(version 20260206)
	(generator "pcbnew")
	(generator_version "10.0")
	(general
		(thickness 1.6)
		(legacy_teardrops no)
	)
	(paper "A4")
	(title_block
		(title "04192023_DAF0TMB3IC0_F0TG_MB_C_brd_V02_OCP.brd")
		(comment 1 "Grand Teton / footprints 515-517 of 8354")
	)
	(layers
		(0 "F.Cu" signal "TOP")
		(4 "In1.Cu" signal "GND")
		(6 "In2.Cu" signal "IN1")
		(8 "In3.Cu" signal "GND1")
		(10 "In4.Cu" signal "IN2")
		(12 "In5.Cu" signal "GND2")
		(14 "In6.Cu" signal "IN3")
		(16 "In7.Cu" signal "GND3")
		(18 "In8.Cu" signal "VCC")
		(20 "In9.Cu" signal "VCC1")
		(22 "In10.Cu" signal "GND4")
		(24 "In11.Cu" signal "IN4")
		(26 "In12.Cu" signal "GND5")
		(28 "In13.Cu" signal "IN5")
		(30 "In14.Cu" signal "GND6")
		(32 "In15.Cu" signal "IN6")
		(34 "In16.Cu" signal "GND7")
		(2 "B.Cu" signal "BOTTOM")
		(9 "F.Adhes" user "F.Adhesive")
		(11 "B.Adhes" user "B.Adhesive")
		(13 "F.Paste" user "Package Geometry/Pastemask Top")
		(15 "B.Paste" user "Package Geometry/Pastemask Bottom")
		(5 "F.SilkS" user "Ref Des/Silkscreen Top")
		(7 "B.SilkS" user "Ref Des/Silkscreen Bottom")
		(1 "F.Mask" user "Board Geometry/Soldermask Top")
		(3 "B.Mask" user "Board Geometry/Soldermask Bottom")
		(17 "Dwgs.User" user "User.Drawings")
		(19 "Cmts.User" user "User.Comments")
		(21 "Eco1.User" user "User.Eco1")
		(23 "Eco2.User" user "User.Eco2")
		(25 "Edge.Cuts" user "Board Geometry/Outline")
		(27 "Margin" user)
		(31 "F.CrtYd" user "Package Geometry/Place Bound Top")
		(29 "B.CrtYd" user "Package Geometry/Place Bound Bottom")
		(35 "F.Fab" user "Ref Des/Assembly Top")
		(33 "B.Fab" user "Ref Des/Assembly Bottom")
	)
	(footprint ""
		(layer "F.Cu")
		(at 398.276318 -76.661264)
		(property "Reference" "C1108"
			(at 0 0 0)
			(layer "F.SilkS")
			(hide yes)
			(effects
				(font
					(size 1.27 1.27)
				)
			)
		)
		(property "Value" ""
			(at 0 0 0)
			(layer "F.Fab")
			(effects
				(font
					(size 1.27 1.27)
				)
			)
		)
		(duplicate_pad_numbers_are_jumpers no)
		(fp_line
			(start -0.7874 -0.4064)
			(end 0.7874 -0.4064)
			(stroke
				(width 0.1524)
				(type default)
			)
			(layer "F.SilkS")
		)
		(fp_line
			(start -0.7874 0.4064)
			(end -0.7874 -0.4064)
			(stroke
				(width 0.1524)
				(type default)
			)
			(layer "F.SilkS")
		)
		(fp_line
			(start 0.7874 -0.4064)
			(end 0.7874 0.4064)
			(stroke
				(width 0.1524)
				(type default)
			)
			(layer "F.SilkS")
		)
		(fp_line
			(start 0.7874 0.4064)
			(end -0.7874 0.4064)
			(stroke
				(width 0.1524)
				(type default)
			)
			(layer "F.SilkS")
		)
		(fp_line
			(start -0.67945 -0.305054)
			(end -0.12065 -0.305054)
			(stroke
				(width 0.1)
				(type default)
			)
			(layer "F.Fab")
		)
		(fp_line
			(start -0.67945 0.3048)
			(end -0.67945 -0.305054)
			(stroke
				(width 0.1)
				(type default)
			)
			(layer "F.Fab")
		)
		(fp_line
			(start -0.12065 -0.305054)
			(end -0.12065 -0.2794)
			(stroke
				(width 0.1)
				(type default)
			)
			(layer "F.Fab")
		)
		(fp_line
			(start -0.12065 -0.2794)
			(end 0.12065 -0.2794)
			(stroke
				(width 0.1)
				(type default)
			)
			(layer "F.Fab")
		)
		(fp_line
			(start -0.12065 0.2794)
			(end -0.12065 0.3048)
			(stroke
				(width 0.1)
				(type default)
			)
			(layer "F.Fab")
		)
		(fp_line
			(start -0.12065 0.3048)
			(end -0.67945 0.3048)
			(stroke
				(width 0.1)
				(type default)
			)
			(layer "F.Fab")
		)
		(fp_line
			(start 0.120396 0.2794)
			(end -0.12065 0.2794)
			(stroke
				(width 0.1)
				(type default)
			)
			(layer "F.Fab")
		)
		(fp_line
			(start 0.120396 0.3048)
			(end 0.120396 0.2794)
			(stroke
				(width 0.1)
				(type default)
			)
			(layer "F.Fab")
		)
		(fp_line
			(start 0.12065 -0.3048)
			(end 0.67945 -0.3048)
			(stroke
				(width 0.1)
				(type default)
			)
			(layer "F.Fab")
		)
		(fp_line
			(start 0.12065 -0.2794)
			(end 0.12065 -0.3048)
			(stroke
				(width 0.1)
				(type default)
			)
			(layer "F.Fab")
		)
		(fp_line
			(start 0.67945 -0.3048)
			(end 0.67945 0.3048)
			(stroke
				(width 0.1)
				(type default)
			)
			(layer "F.Fab")
		)
		(fp_line
			(start 0.67945 0.3048)
			(end 0.120396 0.3048)
			(stroke
				(width 0.1)
				(type default)
			)
			(layer "F.Fab")
		)
		(pad "1" smd circle
			(at -0.40005 0)
			(size 0 0)
			(layers "F.Cu" "F.Mask" "F.Paste")
			(net "P12V_OCP_SFF")
		)
		(pad "2" smd circle
			(at 0.40005 0)
			(size 0 0)
			(layers "F.Cu" "F.Mask" "F.Paste")
			(net "GND")
		)
	)
	(footprint ""
		(layer "F.Cu")
		(at 351.407222 -425.295314)
		(property "Reference" "R4562"
			(at 0 0 0)
			(layer "F.SilkS")
			(hide yes)
			(effects
				(font
					(size 1.27 1.27)
				)
			)
		)
		(property "Value" ""
			(at 0 0 0)
			(layer "F.Fab")
			(effects
				(font
					(size 1.27 1.27)
				)
			)
		)
		(duplicate_pad_numbers_are_jumpers no)
		(fp_line
			(start -0.7874 -0.4064)
			(end 0.7874 -0.4064)
			(stroke
				(width 0.1524)
				(type default)
			)
			(layer "F.SilkS")
		)
		(fp_line
			(start -0.7874 0.4064)
			(end -0.7874 -0.4064)
			(stroke
				(width 0.1524)
				(type default)
			)
			(layer "F.SilkS")
		)
		(fp_line
			(start 0.7874 -0.4064)
			(end 0.7874 0.4064)
			(stroke
				(width 0.1524)
				(type default)
			)
			(layer "F.SilkS")
		)
		(fp_line
			(start 0.7874 0.4064)
			(end -0.7874 0.4064)
			(stroke
				(width 0.1524)
				(type default)
			)
			(layer "F.SilkS")
		)
		(fp_line
			(start -0.67945 -0.305054)
			(end -0.12065 -0.305054)
			(stroke
				(width 0.1)
				(type default)
			)
			(layer "F.Fab")
		)
		(fp_line
			(start -0.67945 0.3048)
			(end -0.67945 -0.305054)
			(stroke
				(width 0.1)
				(type default)
			)
			(layer "F.Fab")
		)
		(fp_line
			(start -0.12065 -0.305054)
			(end -0.12065 -0.2794)
			(stroke
				(width 0.1)
				(type default)
			)
			(layer "F.Fab")
		)
		(fp_line
			(start -0.12065 -0.2794)
			(end 0.12065 -0.2794)
			(stroke
				(width 0.1)
				(type default)
			)
			(layer "F.Fab")
		)
		(fp_line
			(start -0.12065 0.2794)
			(end -0.12065 0.3048)
			(stroke
				(width 0.1)
				(type default)
			)
			(layer "F.Fab")
		)
		(fp_line
			(start -0.12065 0.3048)
			(end -0.67945 0.3048)
			(stroke
				(width 0.1)
				(type default)
			)
			(layer "F.Fab")
		)
		(fp_line
			(start 0.120396 0.2794)
			(end -0.12065 0.2794)
			(stroke
				(width 0.1)
				(type default)
			)
			(layer "F.Fab")
		)
		(fp_line
			(start 0.120396 0.3048)
			(end 0.120396 0.2794)
			(stroke
				(width 0.1)
				(type default)
			)
			(layer "F.Fab")
		)
		(fp_line
			(start 0.12065 -0.3048)
			(end 0.67945 -0.3048)
			(stroke
				(width 0.1)
				(type default)
			)
			(layer "F.Fab")
		)
		(fp_line
			(start 0.12065 -0.2794)
			(end 0.12065 -0.3048)
			(stroke
				(width 0.1)
				(type default)
			)
			(layer "F.Fab")
		)
		(fp_line
			(start 0.67945 -0.3048)
			(end 0.67945 0.3048)
			(stroke
				(width 0.1)
				(type default)
			)
			(layer "F.Fab")
		)
		(fp_line
			(start 0.67945 0.3048)
			(end 0.120396 0.3048)
			(stroke
				(width 0.1)
				(type default)
			)
			(layer "F.Fab")
		)
		(pad "1" smd circle
			(at -0.40005 0)
			(size 0 0)
			(layers "F.Cu" "F.Mask" "F.Paste")
			(net "P3V3_AUX")
		)
		(pad "2" smd circle
			(at 0.40005 0)
			(size 0 0)
			(layers "F.Cu" "F.Mask" "F.Paste")
			(net "SWB_HSC_PWRGD")
		)
	)
	(footprint ""
		(layer "F.Cu")
		(at 169.349166 -416.929316 90)
		(property "Reference" "R812"
			(at 0 0 90)
			(layer "F.SilkS")
			(hide yes)
			(effects
				(font
					(size 1.27 1.27)
				)
			)
		)
		(property "Value" ""
			(at 0 0 90)
			(layer "F.Fab")
			(effects
				(font
					(size 1.27 1.27)
				)
			)
		)
		(duplicate_pad_numbers_are_jumpers no)
		(fp_line
			(start 0.32512 -0.175006)
			(end 0.32512 0.175006)
			(stroke
				(width 0.1)
				(type default)
			)
			(layer "F.Fab")
		)
		(fp_line
			(start -0.32512 -0.175006)
			(end 0.32512 -0.175006)
			(stroke
				(width 0.1)
				(type default)
			)
			(layer "F.Fab")
		)
		(fp_line
			(start 0.32512 0.175006)
			(end -0.32512 0.175006)
			(stroke
				(width 0.1)
				(type default)
			)
			(layer "F.Fab")
		)
		(fp_line
			(start -0.32512 0.175006)
			(end -0.32512 -0.175006)
			(stroke
				(width 0.1)
				(type default)
			)
			(layer "F.Fab")
		)
		(pad "1" smd rect
			(at -0.2667 0 90)
			(size 0.3048 0.381)
			(layers "F.Cu" "F.Mask" "F.Paste")
			(net "P1V8_CPU1_RT_1D")
		)
		(pad "2" smd rect
			(at 0.2667 0 270)
			(size 0.3048 0.381)
			(layers "F.Cu" "F.Mask" "F.Paste")
			(net "SMB_RT_CPU1_P3_ROM_R_SCL")
		)
	)
)
